# S9S_MB_2U (Grand Teton) — schematic netlist excerpt (pin names and nets, part order shuffled) for the footprints in the layout excerpt that follows; sources: Cadence DE-HDL packaged netlist, KiCad conversion of 03242023_DA0F0TMBIJ0_F0T_Motherboard_J_brd_V01_OCP.brd

R614  Q_RES  1K 1% EMPTY  pkg 0402LF  page 199 : A = FM_JTAG_ODT_DISABLE ; B = GND

U68  74CBTLV3126PW  IC  pkg TSSOP14  page 154
  \1oe\  = FB_BMC_ISOLATE
  \1a\  = NCSI_BMC_TXD1_R
  \1b\  = NCSI_OCP_SFF_TXD1
  \2oe\  = FB_BMC_ISOLATE
  \2a\  = NCSI_BMC_TXD0_R
  \2b\  = NCSI_OCP_SFF_TXD0
  GND  = GND
  \3b\  = NCSI_OCP_SFF_TX_EN
  \3a\  = NCSI_BMC_TX_EN_R
  \3oe\  = FB_BMC_ISOLATE
  \4b\  = OCP_SFF_ISO2_RBT_ARB_OUT
  \4a\  = OCP_SFF_RBT_ARB_OUT
  \4oe\  = FB_BMC_ISOLATE
  VCC  = P3V3_AUX

(kicad_pcb
	(version 20260206)
	(generator "pcbnew")
	(generator_version "10.0")
	(general
		(thickness 1.6)
		(legacy_teardrops no)
	)
	(paper "A4")
	(title_block
		(title "03242023_DA0F0TMBIJ0_F0T_Motherboard_J_brd_V01_OCP.brd")
		(comment 1 "Grand Teton / footprints 4376-4377 of 6105")
	)
	(layers
		(0 "F.Cu" signal "TOP")
		(4 "In1.Cu" signal "GND")
		(6 "In2.Cu" signal "IN1")
		(8 "In3.Cu" signal "GND1")
		(10 "In4.Cu" signal "IN2")
		(12 "In5.Cu" signal "GND2")
		(14 "In6.Cu" signal "IN3")
		(16 "In7.Cu" signal "GND3")
		(18 "In8.Cu" signal "VCC")
		(20 "In9.Cu" signal "VCC1")
		(22 "In10.Cu" signal "GND4")
		(24 "In11.Cu" signal "IN4")
		(26 "In12.Cu" signal "GND5")
		(28 "In13.Cu" signal "IN5")
		(30 "In14.Cu" signal "GND6")
		(32 "In15.Cu" signal "IN6")
		(34 "In16.Cu" signal "GND7")
		(2 "B.Cu" signal "BOTTOM")
		(9 "F.Adhes" user "F.Adhesive")
		(11 "B.Adhes" user "B.Adhesive")
		(13 "F.Paste" user "Package Geometry/Pastemask Top")
		(15 "B.Paste" user "Package Geometry/Pastemask Bottom")
		(5 "F.SilkS" user "Ref Des/Silkscreen Top")
		(7 "B.SilkS" user "Ref Des/Silkscreen Bottom")
		(1 "F.Mask" user "Board Geometry/Soldermask Top")
		(3 "B.Mask" user "Board Geometry/Soldermask Bottom")
		(17 "Dwgs.User" user "User.Drawings")
		(19 "Cmts.User" user "User.Comments")
		(21 "Eco1.User" user "User.Eco1")
		(23 "Eco2.User" user "User.Eco2")
		(25 "Edge.Cuts" user "Board Geometry/Outline")
		(27 "Margin" user)
		(31 "F.CrtYd" user "Package Geometry/Place Bound Top")
		(29 "B.CrtYd" user "Package Geometry/Place Bound Bottom")
		(35 "F.Fab" user "Ref Des/Assembly Top")
		(33 "B.Fab" user "Ref Des/Assembly Bottom")
	)
	(footprint ""
		(layer "B.Cu")
		(at 324.98919 -28.45435 90)
		(property "Reference" "R614"
			(at 0 0 90)
			(layer "B.SilkS")
			(hide yes)
			(effects
				(font
					(size 1.27 1.27)
				)
				(justify mirror)
			)
		)
		(property "Value" ""
			(at 0 0 90)
			(layer "B.Fab")
			(effects
				(font
					(size 1.27 1.27)
				)
				(justify mirror)
			)
		)
		(duplicate_pad_numbers_are_jumpers no)
		(fp_line
			(start 0.7874 -0.4064)
			(end -0.7874 -0.4064)
			(stroke
				(width 0.1524)
				(type default)
			)
			(layer "B.SilkS")
		)
		(fp_line
			(start -0.7874 -0.4064)
			(end -0.7874 0.4064)
			(stroke
				(width 0.1524)
				(type default)
			)
			(layer "B.SilkS")
		)
		(fp_line
			(start 0.7874 0.4064)
			(end 0.7874 -0.4064)
			(stroke
				(width 0.1524)
				(type default)
			)
			(layer "B.SilkS")
		)
		(fp_line
			(start -0.7874 0.4064)
			(end 0.7874 0.4064)
			(stroke
				(width 0.1524)
				(type default)
			)
			(layer "B.SilkS")
		)
		(fp_line
			(start 0.67945 -0.305054)
			(end 0.12065 -0.305054)
			(stroke
				(width 0.1)
				(type default)
			)
			(layer "B.Fab")
		)
		(fp_line
			(start 0.12065 -0.305054)
			(end 0.12065 -0.2794)
			(stroke
				(width 0.1)
				(type default)
			)
			(layer "B.Fab")
		)
		(fp_line
			(start -0.12065 -0.3048)
			(end -0.67945 -0.3048)
			(stroke
				(width 0.1)
				(type default)
			)
			(layer "B.Fab")
		)
		(fp_line
			(start -0.67945 -0.3048)
			(end -0.67945 0.3048)
			(stroke
				(width 0.1)
				(type default)
			)
			(layer "B.Fab")
		)
		(fp_line
			(start 0.12065 -0.2794)
			(end -0.12065 -0.2794)
			(stroke
				(width 0.1)
				(type default)
			)
			(layer "B.Fab")
		)
		(fp_line
			(start -0.12065 -0.2794)
			(end -0.12065 -0.3048)
			(stroke
				(width 0.1)
				(type default)
			)
			(layer "B.Fab")
		)
		(fp_line
			(start 0.12065 0.2794)
			(end 0.12065 0.3048)
			(stroke
				(width 0.1)
				(type default)
			)
			(layer "B.Fab")
		)
		(fp_line
			(start -0.120396 0.2794)
			(end 0.12065 0.2794)
			(stroke
				(width 0.1)
				(type default)
			)
			(layer "B.Fab")
		)
		(fp_line
			(start 0.67945 0.3048)
			(end 0.67945 -0.305054)
			(stroke
				(width 0.1)
				(type default)
			)
			(layer "B.Fab")
		)
		(fp_line
			(start 0.12065 0.3048)
			(end 0.67945 0.3048)
			(stroke
				(width 0.1)
				(type default)
			)
			(layer "B.Fab")
		)
		(fp_line
			(start -0.120396 0.3048)
			(end -0.120396 0.2794)
			(stroke
				(width 0.1)
				(type default)
			)
			(layer "B.Fab")
		)
		(fp_line
			(start -0.67945 0.3048)
			(end -0.120396 0.3048)
			(stroke
				(width 0.1)
				(type default)
			)
			(layer "B.Fab")
		)
		(pad "1" smd circle
			(at 0.40005 0 270)
			(size 0 0)
			(layers "B.Cu" "B.Mask" "B.Paste")
			(net "FM_JTAG_ODT_DISABLE")
		)
		(pad "2" smd circle
			(at -0.40005 0 270)
			(size 0 0)
			(layers "B.Cu" "B.Mask" "B.Paste")
			(net "GND")
		)
	)
	(footprint ""
		(layer "B.Cu")
		(at 211.836 -70.852792 180)
		(property "Reference" "U68"
			(at -0.51562 -3.679698 0)
			(unlocked yes)
			(layer "B.SilkS")
			(effects
				(font
					(size 0.7874 0.5842)
					(thickness 0.1524)
				)
				(justify left mirror)
			)
		)
		(property "Value" ""
			(at 0 0 0)
			(layer "B.Fab")
			(effects
				(font
					(size 1.27 1.27)
				)
				(justify mirror)
			)
		)
		(duplicate_pad_numbers_are_jumpers no)
		(fp_line
			(start 2.0066 2.5527)
			(end 2.0066 -2.5527)
			(stroke
				(width 0.1524)
				(type default)
			)
			(layer "B.SilkS")
		)
		(fp_line
			(start 2.0066 -2.5527)
			(end 0.5715 -2.5527)
			(stroke
				(width 0.1524)
				(type default)
			)
			(layer "B.SilkS")
		)
		(fp_line
			(start 0.5715 -2.5527)
			(end 0 -1.9812)
			(stroke
				(width 0.1524)
				(type default)
			)
			(layer "B.SilkS")
		)
		(fp_line
			(start 0 -1.9812)
			(end -0.5715 -2.5527)
			(stroke
				(width 0.1524)
				(type default)
			)
			(layer "B.SilkS")
		)
		(fp_line
			(start -0.5715 -2.5527)
			(end -2.0066 -2.5527)
			(stroke
				(width 0.1524)
				(type default)
			)
			(layer "B.SilkS")
		)
		(fp_line
			(start -2.0066 2.5527)
			(end 2.0066 2.5527)
			(stroke
				(width 0.1524)
				(type default)
			)
			(layer "B.SilkS")
		)
		(fp_line
			(start -2.0066 -2.5527)
			(end -2.0066 2.5527)
			(stroke
				(width 0.1524)
				(type default)
			)
			(layer "B.SilkS")
		)
		(fp_poly
			(pts
				(xy 3.81 -1.905) (xy 4.36372 -2.233168) (xy 4.36372 -1.608328)
			)
			(stroke
				(width 0)
				(type default)
			)
			(fill yes)
			(layer "B.SilkS")
		)
		(fp_line
			(start 2.249932 2.549906)
			(end 2.249932 -2.549906)
			(stroke
				(width 0.1)
				(type default)
			)
			(layer "B.Fab")
		)
		(fp_line
			(start 2.249932 -2.549906)
			(end -2.249932 -2.549906)
			(stroke
				(width 0.1)
				(type default)
			)
			(layer "B.Fab")
		)
		(fp_line
			(start -2.249932 2.549906)
			(end 2.249932 2.549906)
			(stroke
				(width 0.1)
				(type default)
			)
			(layer "B.Fab")
		)
		(fp_line
			(start -2.249932 -2.549906)
			(end -2.249932 2.549906)
			(stroke
				(width 0.1)
				(type default)
			)
			(layer "B.Fab")
		)
		(fp_poly
			(pts
				(xy 4.36372 -1.608328) (xy 4.36372 -2.233168) (xy 3.81 -1.905)
			)
			(stroke
				(width 0)
				(type default)
			)
			(fill yes)
			(layer "B.Fab")
		)
		(pad "1" smd rect
			(at 2.921 -1.949958 90)
			(size 0.3556 1.4986)
			(layers "B.Cu" "B.Mask" "B.Paste")
			(net "FB_BMC_ISOLATE")
		)
		(pad "2" smd rect
			(at 2.921 -1.299972 90)
			(size 0.3556 1.4986)
			(layers "B.Cu" "B.Mask" "B.Paste")
			(net "NCSI_BMC_TXD1_R")
		)
		(pad "3" smd rect
			(at 2.921 -0.649986 90)
			(size 0.3556 1.4986)
			(layers "B.Cu" "B.Mask" "B.Paste")
			(net "NCSI_OCP_SFF_TXD1")
		)
		(pad "4" smd rect
			(at 2.921 0 90)
			(size 0.3556 1.4986)
			(layers "B.Cu" "B.Mask" "B.Paste")
			(net "FB_BMC_ISOLATE")
		)
		(pad "5" smd rect
			(at 2.921 0.649986 90)
			(size 0.3556 1.4986)
			(layers "B.Cu" "B.Mask" "B.Paste")
			(net "NCSI_BMC_TXD0_R")
		)
		(pad "6" smd rect
			(at 2.921 1.299972 90)
			(size 0.3556 1.4986)
			(layers "B.Cu" "B.Mask" "B.Paste")
			(net "NCSI_OCP_SFF_TXD0")
		)
		(pad "7" smd rect
			(at 2.921 1.949958 90)
			(size 0.3556 1.4986)
			(layers "B.Cu" "B.Mask" "B.Paste")
			(net "GND")
		)
		(pad "8" smd rect
			(at -2.921 1.949958 90)
			(size 0.3556 1.4986)
			(layers "B.Cu" "B.Mask" "B.Paste")
			(net "NCSI_OCP_SFF_TX_EN")
		)
		(pad "9" smd rect
			(at -2.921 1.299972 90)
			(size 0.3556 1.4986)
			(layers "B.Cu" "B.Mask" "B.Paste")
			(net "NCSI_BMC_TX_EN_R")
		)
		(pad "10" smd rect
			(at -2.921 0.649986 90)
			(size 0.3556 1.4986)
			(layers "B.Cu" "B.Mask" "B.Paste")
			(net "FB_BMC_ISOLATE")
		)
		(pad "11" smd rect
			(at -2.921 0 90)
			(size 0.3556 1.4986)
			(layers "B.Cu" "B.Mask" "B.Paste")
			(net "OCP_SFF_ISO2_RBT_ARB_OUT")
		)
		(pad "12" smd rect
			(at -2.921 -0.649986 90)
			(size 0.3556 1.4986)
			(layers "B.Cu" "B.Mask" "B.Paste")
			(net "OCP_SFF_RBT_ARB_OUT")
		)
		(pad "13" smd rect
			(at -2.921 -1.299972 90)
			(size 0.3556 1.4986)
			(layers "B.Cu" "B.Mask" "B.Paste")
			(net "FB_BMC_ISOLATE")
		)
		(pad "14" smd rect
			(at -2.921 -1.949958 90)
			(size 0.3556 1.4986)
			(layers "B.Cu" "B.Mask" "B.Paste")
			(net "P3V3_AUX")
		)
	)
)
